# BASEBOARD_FAB2 (Tioga Pass) — schematic netlist excerpt (pin names and nets, part order shuffled) for the footprints in the layout excerpt that follows; sources: Cadence DE-HDL packaged netlist, KiCad conversion of Wiwynn_Tioga_Pass_MB.brd

R25W113  RES  4.75K 1% EMPTY  pkg 0402  page 150 : A = P3V3_STBY ; B = RMII_BMC_PCH_SPRNGVLLE_TXD1_R
C4D50  CAP  0.220UF 16V 10% X7R  pkg 0402  page 202 : A = VR_PVCCIN_CPU0_PH2_BOOT ; B = VR_PVCCIN_CPU0_PH2_PHASE
R4E20  RES  2.26K 1.0% EMPTY  pkg 0402  page 201 : A = P3V3_STBY ; B = PU_VR_PVCCIN_CPU0_FLT1_SMBALT_N

(kicad_pcb
	(version 20260206)
	(generator "pcbnew")
	(generator_version "10.0")
	(general
		(thickness 1.6)
		(legacy_teardrops no)
	)
	(paper "A4")
	(title_block
		(title "Wiwynn_Tioga_Pass_MB.brd")
		(comment 1 "Tioga Pass / footprints 114-116 of 4770")
	)
	(layers
		(0 "F.Cu" signal "TOP")
		(4 "In1.Cu" signal "L2GND")
		(6 "In2.Cu" signal "L3")
		(8 "In3.Cu" signal "L4GND")
		(10 "In4.Cu" signal "L5")
		(12 "In5.Cu" signal "L6GND")
		(14 "In6.Cu" signal "L7VCC")
		(16 "In7.Cu" signal "L8VCC")
		(18 "In8.Cu" signal "L9GND")
		(20 "In9.Cu" signal "L10")
		(22 "In10.Cu" signal "L11GND")
		(24 "In11.Cu" signal "L12")
		(26 "In12.Cu" signal "L13GND")
		(2 "B.Cu" signal "BOTTOM")
		(9 "F.Adhes" user "F.Adhesive")
		(11 "B.Adhes" user "B.Adhesive")
		(13 "F.Paste" user "Package Geometry/Pastemask Top")
		(15 "B.Paste" user "Package Geometry/Pastemask Bottom")
		(5 "F.SilkS" user "Ref Des/Silkscreen Top")
		(7 "B.SilkS" user "Ref Des/Silkscreen Bottom")
		(1 "F.Mask" user "Board Geometry/Soldermask Top")
		(3 "B.Mask" user "Board Geometry/Soldermask Bottom")
		(17 "Dwgs.User" user "User.Drawings")
		(19 "Cmts.User" user "User.Comments")
		(21 "Eco1.User" user "User.Eco1")
		(23 "Eco2.User" user "User.Eco2")
		(25 "Edge.Cuts" user "Board Geometry/Outline")
		(27 "Margin" user)
		(31 "F.CrtYd" user "Package Geometry/Place Bound Top")
		(29 "B.CrtYd" user "Package Geometry/Place Bound Bottom")
		(35 "F.Fab" user "Ref Des/Assembly Top")
		(33 "B.Fab" user "Ref Des/Assembly Bottom")
	)
	(footprint ""
		(layer "F.Cu")
		(at 184.985914 -61.976 180)
		(property "Reference" "R4E20"
			(at 0 0 180)
			(layer "F.SilkS")
			(hide yes)
			(effects
				(font
					(size 1.27 1.27)
				)
			)
		)
		(property "Value" ""
			(at 0 0 180)
			(layer "F.Fab")
			(effects
				(font
					(size 1.27 1.27)
				)
			)
		)
		(duplicate_pad_numbers_are_jumpers no)
		(fp_rect
			(start 0.2794 -0.1016)
			(end -0.2794 0.9906)
			(stroke
				(width 0)
				(type default)
			)
			(fill no)
			(layer "F.CrtYd")
		)
		(fp_line
			(start 0.2794 0.9906)
			(end 0.2794 -0.1016)
			(stroke
				(width 0.1)
				(type default)
			)
			(layer "F.Fab")
		)
		(fp_line
			(start 0.2794 -0.1016)
			(end -0.2794 -0.1016)
			(stroke
				(width 0.1)
				(type default)
			)
			(layer "F.Fab")
		)
		(fp_line
			(start -0.2794 0.9906)
			(end 0.2794 0.9906)
			(stroke
				(width 0.1)
				(type default)
			)
			(layer "F.Fab")
		)
		(fp_line
			(start -0.2794 -0.1016)
			(end -0.2794 0.9906)
			(stroke
				(width 0.1)
				(type default)
			)
			(layer "F.Fab")
		)
		(pad "1" smd rect
			(at 0 0 180)
			(size 0.508 0.508)
			(layers "F.Cu" "F.Mask" "F.Paste")
			(net "P3V3_STBY")
		)
		(pad "2" smd rect
			(at 0 0.889 180)
			(size 0.508 0.508)
			(layers "F.Cu" "F.Mask" "F.Paste")
			(net "PU_VR_PVCCIN_CPU0_FLT1_SMBALT_N")
		)
		(zone
			(layer "F.Cu")
			(hatch none 0.5)
			(connect_pads
				(clearance 0)
			)
			(min_thickness 0.25)
			(keepout
				(tracks not_allowed)
				(vias allowed)
				(pads allowed)
				(copperpour not_allowed)
				(footprints allowed)
			)
			(placement
				(enabled no)
				(sheetname "")
			)
			(fill
				(thermal_gap 0.5)
				(thermal_bridge_width 0.5)
				(island_removal_mode 0)
			)
			(polygon
				(pts
					(xy 184.731914 -62.23) (xy 185.239914 -62.23) (xy 185.239914 -62.611) (xy 184.731914 -62.611)
				)
			)
		)
		(zone
			(layer "F.Cu")
			(hatch none 0.5)
			(connect_pads
				(clearance 0)
			)
			(min_thickness 0.25)
			(keepout
				(tracks allowed)
				(vias not_allowed)
				(pads allowed)
				(copperpour not_allowed)
				(footprints allowed)
			)
			(placement
				(enabled no)
				(sheetname "")
			)
			(fill
				(thermal_gap 0.5)
				(thermal_bridge_width 0.5)
				(island_removal_mode 0)
			)
			(polygon
				(pts
					(xy 184.731914 -62.23) (xy 185.239914 -62.23) (xy 185.239914 -62.611) (xy 184.731914 -62.611)
				)
			)
		)
	)
	(footprint ""
		(layer "F.Cu")
		(at 193.929 -67.1576 90)
		(property "Reference" "C4D50"
			(at 0 0 90)
			(layer "F.SilkS")
			(hide yes)
			(effects
				(font
					(size 1.27 1.27)
				)
			)
		)
		(property "Value" ""
			(at 0 0 90)
			(layer "F.Fab")
			(effects
				(font
					(size 1.27 1.27)
				)
			)
		)
		(duplicate_pad_numbers_are_jumpers no)
		(fp_rect
			(start -0.3048 0.9906)
			(end 0.3048 -0.1016)
			(stroke
				(width 0)
				(type default)
			)
			(fill no)
			(layer "F.CrtYd")
		)
		(fp_line
			(start 0.3048 -0.1016)
			(end -0.3048 -0.1016)
			(stroke
				(width 0.1)
				(type default)
			)
			(layer "F.Fab")
		)
		(fp_line
			(start -0.3048 -0.1016)
			(end -0.3048 0.9906)
			(stroke
				(width 0.1)
				(type default)
			)
			(layer "F.Fab")
		)
		(fp_line
			(start 0.3048 0.9906)
			(end 0.3048 -0.1016)
			(stroke
				(width 0.1)
				(type default)
			)
			(layer "F.Fab")
		)
		(fp_line
			(start -0.3048 0.9906)
			(end 0.3048 0.9906)
			(stroke
				(width 0.1)
				(type default)
			)
			(layer "F.Fab")
		)
		(pad "1" smd rect
			(at 0 0 90)
			(size 0.508 0.508)
			(layers "F.Cu" "F.Mask" "F.Paste")
			(net "VR_PVCCIN_CPU0_PH2_BOOT")
		)
		(pad "2" smd rect
			(at 0 0.889 90)
			(size 0.508 0.508)
			(layers "F.Cu" "F.Mask" "F.Paste")
			(net "VR_PVCCIN_CPU0_PH2_PHASE")
		)
		(zone
			(layer "F.Cu")
			(hatch none 0.5)
			(connect_pads
				(clearance 0)
			)
			(min_thickness 0.25)
			(keepout
				(tracks not_allowed)
				(vias allowed)
				(pads allowed)
				(copperpour not_allowed)
				(footprints allowed)
			)
			(placement
				(enabled no)
				(sheetname "")
			)
			(fill
				(thermal_gap 0.5)
				(thermal_bridge_width 0.5)
				(island_removal_mode 0)
			)
			(polygon
				(pts
					(xy 194.564 -66.9036) (xy 194.564 -67.4116) (xy 194.183 -67.4116) (xy 194.183 -66.9036)
				)
			)
		)
		(zone
			(layer "F.Cu")
			(hatch none 0.5)
			(connect_pads
				(clearance 0)
			)
			(min_thickness 0.25)
			(keepout
				(tracks allowed)
				(vias not_allowed)
				(pads allowed)
				(copperpour not_allowed)
				(footprints allowed)
			)
			(placement
				(enabled no)
				(sheetname "")
			)
			(fill
				(thermal_gap 0.5)
				(thermal_bridge_width 0.5)
				(island_removal_mode 0)
			)
			(polygon
				(pts
					(xy 194.564 -66.9036) (xy 194.564 -67.4116) (xy 194.183 -67.4116) (xy 194.183 -66.9036)
				)
			)
		)
	)
	(footprint ""
		(layer "F.Cu")
		(at 402.717 -24.892)
		(property "Reference" "R25W113"
			(at -0.8382 -0.67818 0)
			(unlocked yes)
			(layer "F.SilkS")
			(effects
				(font
					(size 0.4064 0.254)
					(thickness 0.1524)
				)
				(justify left)
			)
		)
		(property "Value" ""
			(at 0 0 0)
			(layer "F.Fab")
			(effects
				(font
					(size 1.27 1.27)
				)
			)
		)
		(duplicate_pad_numbers_are_jumpers no)
		(fp_poly
			(pts
				(xy -0.2794 -0.1016) (xy 0.2794 -0.1016) (xy 0.2794 0.9906) (xy -0.2794 0.9906)
			)
			(stroke
				(width 0)
				(type default)
			)
			(fill no)
			(layer "F.CrtYd")
		)
		(fp_line
			(start -0.2794 -0.1016)
			(end -0.2794 0.9906)
			(stroke
				(width 0.1)
				(type default)
			)
			(layer "F.Fab")
		)
		(fp_line
			(start -0.2794 0.9906)
			(end 0.2794 0.9906)
			(stroke
				(width 0.1)
				(type default)
			)
			(layer "F.Fab")
		)
		(fp_line
			(start 0.2794 -0.1016)
			(end -0.2794 -0.1016)
			(stroke
				(width 0.1)
				(type default)
			)
			(layer "F.Fab")
		)
		(fp_line
			(start 0.2794 0.9906)
			(end 0.2794 -0.1016)
			(stroke
				(width 0.1)
				(type default)
			)
			(layer "F.Fab")
		)
		(pad "1" smd rect
			(at 0 0)
			(size 0.508 0.508)
			(layers "F.Cu" "F.Mask" "F.Paste")
			(net "P3V3_STBY")
		)
		(pad "2" smd rect
			(at 0 0.889)
			(size 0.508 0.508)
			(layers "F.Cu" "F.Mask" "F.Paste")
			(net "RMII_BMC_PCH_SPRNGVLLE_TXD1_R")
		)
		(zone
			(layer "F.Cu")
			(hatch none 0.5)
			(connect_pads
				(clearance 0)
			)
			(min_thickness 0.25)
			(keepout
				(tracks allowed)
				(vias not_allowed)
				(pads allowed)
				(copperpour not_allowed)
				(footprints allowed)
			)
			(placement
				(enabled no)
				(sheetname "")
			)
			(fill
				(thermal_gap 0.5)
				(thermal_bridge_width 0.5)
				(island_removal_mode 0)
			)
			(polygon
				(pts
					(xy 402.463 -24.638) (xy 402.971 -24.638) (xy 402.971 -24.257) (xy 402.463 -24.257)
				)
			)
		)
		(zone
			(layer "F.Cu")
			(hatch none 0.5)
			(connect_pads
				(clearance 0)
			)
			(min_thickness 0.25)
			(keepout
				(tracks not_allowed)
				(vias allowed)
				(pads allowed)
				(copperpour not_allowed)
				(footprints allowed)
			)
			(placement
				(enabled no)
				(sheetname "")
			)
			(fill
				(thermal_gap 0.5)
				(thermal_bridge_width 0.5)
				(island_removal_mode 0)
			)
			(polygon
				(pts
					(xy 402.463 -24.257) (xy 402.971 -24.257) (xy 402.971 -24.638) (xy 402.463 -24.638)
				)
			)
		)
	)
)
